(kicad_pcb
	(version 20241229)
	(generator "pcbnew")
	(generator_version "9.0")
	(general
		(thickness 1.6296)
		(legacy_teardrops no)
	)
	(paper "A3")
	(title_block
		(title "Thunderbolt to 10GbE adapter")
		(date "2026-04-21")
		(rev "1.1.0")
		(company "Antmicro Ltd")
		(comment 1 "www.antmicro.com")
		(comment 9 "footprints 556-559 of 703")
	)
	(layers
		(0 "F.Cu" signal)
		(4 "In1.Cu" signal)
		(6 "In2.Cu" signal)
		(8 "In3.Cu" signal)
		(10 "In4.Cu" signal)
		(12 "In5.Cu" signal)
		(14 "In6.Cu" signal)
		(2 "B.Cu" signal)
		(9 "F.Adhes" user "F.Adhesive")
		(11 "B.Adhes" user "B.Adhesive")
		(13 "F.Paste" user)
		(15 "B.Paste" user)
		(5 "F.SilkS" user "F.Silkscreen")
		(7 "B.SilkS" user "B.Silkscreen")
		(1 "F.Mask" user)
		(3 "B.Mask" user)
		(17 "Dwgs.User" user "User.Drawings")
		(19 "Cmts.User" user "User.Comments")
		(21 "Eco1.User" user "User.Eco1")
		(23 "Eco2.User" user "User.Eco2")
		(25 "Edge.Cuts" user)
		(27 "Margin" user)
		(31 "F.CrtYd" user "F.Courtyard")
		(29 "B.CrtYd" user "B.Courtyard")
		(35 "F.Fab" user)
		(33 "B.Fab" user)
	)
	(footprint "antmicro-footprints:C_Pol_EIA-A"
		(layer "B.Cu")
		(at 155 97.5 180)
		(property "Reference" "C332"
			(at -1.5 1.2 0)
			(layer "B.SilkS")
			(effects
				(font
					(size 0.7 0.7)
					(thickness 0.15)
				)
				(justify left bottom mirror)
			)
		)
		(property "Value" "C_Pol_100u_6V_KEMET-T490-A"
			(at 0 -2 0)
			(layer "B.Fab")
			(effects
				(font
					(size 0.7 0.7)
					(thickness 0.15)
				)
				(justify left bottom mirror)
			)
		)
		(property "Datasheet" "https://www.kemet.com/en/us/capacitors/product/T490A107M006ATE800.html"
			(at 0 0 0)
			(layer "B.Fab")
			(hide yes)
			(effects
				(font
					(size 1.27 1.27)
					(thickness 0.15)
				)
				(justify mirror)
			)
		)
		(property "Description" "Surface Mount Tantalum Capacitor,  Solid SMD 6V 100uF 1206 20% ESR=800mOhms"
			(at 0 0 0)
			(layer "B.Fab")
			(hide yes)
			(effects
				(font
					(size 1.27 1.27)
					(thickness 0.15)
				)
				(justify mirror)
			)
		)
		(property "Val" "100u"
			(at 0 0 180)
			(unlocked yes)
			(layer "B.Fab")
			(hide yes)
			(effects
				(font
					(size 1 1)
					(thickness 0.15)
				)
				(justify mirror)
			)
		)
		(property "MPN" "T490A107M006ATE800"
			(at 0 0 180)
			(unlocked yes)
			(layer "B.Fab")
			(hide yes)
			(effects
				(font
					(size 1 1)
					(thickness 0.15)
				)
				(justify mirror)
			)
		)
		(property "Manufacturer" "KEMET"
			(at 0 0 180)
			(unlocked yes)
			(layer "B.Fab")
			(hide yes)
			(effects
				(font
					(size 1 1)
					(thickness 0.15)
				)
				(justify mirror)
			)
		)
		(property "License" "Apache-2.0"
			(at 0 0 180)
			(unlocked yes)
			(layer "B.Fab")
			(hide yes)
			(effects
				(font
					(size 1 1)
					(thickness 0.15)
				)
				(justify mirror)
			)
		)
		(property "Author" "Antmicro"
			(at 0 0 180)
			(unlocked yes)
			(layer "B.Fab")
			(hide yes)
			(effects
				(font
					(size 1 1)
					(thickness 0.15)
				)
				(justify mirror)
			)
		)
		(property "Voltage" "6V"
			(at 0 0 180)
			(unlocked yes)
			(layer "B.Fab")
			(hide yes)
			(effects
				(font
					(size 1 1)
					(thickness 0.15)
				)
				(justify mirror)
			)
		)
		(property "Dielectric" "template_dielectric"
			(at 0 0 180)
			(unlocked yes)
			(layer "B.Fab")
			(hide yes)
			(effects
				(font
					(size 1 1)
					(thickness 0.15)
				)
				(justify mirror)
			)
		)
		(sheetname "/X710-AT2 power/")
		(sheetfile "x710-at2-power.kicad_sch")
		(attr smd)
		(fp_line
			(start 1.5 0.75)
			(end 1.5 0.85)
			(stroke
				(width 0.12)
				(type solid)
			)
			(layer "B.SilkS")
		)
		(fp_line
			(start 1.5 -0.75)
			(end 1.5 -0.85)
			(stroke
				(width 0.12)
				(type solid)
			)
			(layer "B.SilkS")
		)
		(fp_line
			(start 1.5 -0.85)
			(end -1.5 -0.85)
			(stroke
				(width 0.12)
				(type solid)
			)
			(layer "B.SilkS")
		)
		(fp_line
			(start -1.5 0.85)
			(end 1.5 0.85)
			(stroke
				(width 0.12)
				(type solid)
			)
			(layer "B.SilkS")
		)
		(fp_line
			(start -1.5 0.75)
			(end -1.5 0.85)
			(stroke
				(width 0.12)
				(type solid)
			)
			(layer "B.SilkS")
		)
		(fp_line
			(start -1.5 -0.75)
			(end -1.5 -0.85)
			(stroke
				(width 0.12)
				(type solid)
			)
			(layer "B.SilkS")
		)
		(fp_line
			(start -1.95 1.25)
			(end -1.95 0.95)
			(stroke
				(width 0.12)
				(type solid)
			)
			(layer "B.SilkS")
		)
		(fp_line
			(start -2.1 1.1)
			(end -1.8 1.1)
			(stroke
				(width 0.12)
				(type solid)
			)
			(layer "B.SilkS")
		)
		(fp_line
			(start 2.05 0.85)
			(end 2.05 -0.85)
			(stroke
				(width 0.05)
				(type solid)
			)
			(layer "B.CrtYd")
		)
		(fp_line
			(start 2.05 0.85)
			(end 1.7 0.85)
			(stroke
				(width 0.05)
				(type solid)
			)
			(layer "B.CrtYd")
		)
		(fp_line
			(start 2.05 -0.85)
			(end 1.7 -0.85)
			(stroke
				(width 0.05)
				(type solid)
			)
			(layer "B.CrtYd")
		)
		(fp_line
			(start 1.7 1.05)
			(end -1.7 1.05)
			(stroke
				(width 0.05)
				(type solid)
			)
			(layer "B.CrtYd")
		)
		(fp_line
			(start 1.7 0.85)
			(end 1.7 1.05)
			(stroke
				(width 0.05)
				(type solid)
			)
			(layer "B.CrtYd")
		)
		(fp_line
			(start 1.7 -1.05)
			(end 1.7 -0.85)
			(stroke
				(width 0.05)
				(type solid)
			)
			(layer "B.CrtYd")
		)
		(fp_line
			(start 1.7 -1.05)
			(end -1.7 -1.05)
			(stroke
				(width 0.05)
				(type solid)
			)
			(layer "B.CrtYd")
		)
		(fp_line
			(start -1.7 0.85)
			(end -1.7 1.05)
			(stroke
				(width 0.05)
				(type solid)
			)
			(layer "B.CrtYd")
		)
		(fp_line
			(start -1.7 0.85)
			(end -2.05 0.85)
			(stroke
				(width 0.05)
				(type solid)
			)
			(layer "B.CrtYd")
		)
		(fp_line
			(start -1.7 -0.85)
			(end -2.05 -0.85)
			(stroke
				(width 0.05)
				(type solid)
			)
			(layer "B.CrtYd")
		)
		(fp_line
			(start -1.7 -1.05)
			(end -1.7 -0.85)
			(stroke
				(width 0.05)
				(type solid)
			)
			(layer "B.CrtYd")
		)
		(fp_line
			(start -2.05 0.85)
			(end -2.05 -0.85)
			(stroke
				(width 0.05)
				(type solid)
			)
			(layer "B.CrtYd")
		)
		(fp_rect
			(start -1.601 0.802)
			(end 1.6 -0.8)
			(stroke
				(width 0.1)
				(type solid)
			)
			(fill no)
			(layer "B.Fab")
		)
		(fp_text user "${REFERENCE}"
			(at -2.1 -4.198 0)
			(layer "B.Fab")
			(effects
				(font
					(size 0.7 0.7)
					(thickness 0.15)
				)
				(justify left bottom mirror)
			)
		)
		(fp_text user "Author: Antmicro"
			(at -2.1 -6.198 0)
			(layer "B.Fab")
			(effects
				(font
					(size 0.7 0.7)
					(thickness 0.15)
				)
				(justify left bottom mirror)
			)
		)
		(fp_text user "License: Apache-2.0"
			(at -2.1 -5.198 0)
			(layer "B.Fab")
			(effects
				(font
					(size 0.7 0.7)
					(thickness 0.15)
				)
				(justify left bottom mirror)
			)
		)
		(pad "1" smd roundrect
			(at -1.2 0 180)
			(size 1.2 1.2)
			(layers "B.Cu" "B.Mask" "B.Paste")
			(roundrect_rratio 0.1)
			(net 136 "+1V0")
			(pintype "passive")
		)
		(pad "2" smd roundrect
			(at 1.2 0 180)
			(size 1.2 1.2)
			(layers "B.Cu" "B.Mask" "B.Paste")
			(roundrect_rratio 0.1)
			(net 23 "GND")
			(pintype "passive")
		)
	)
	(footprint "antmicro-footprints:L_0402_1005Metric"
		(layer "B.Cu")
		(at 159 137.5 180)
		(descr "Inductor SMD 0402")
		(tags "Inductor SMD 0402")
		(property "Reference" "L12"
			(at 1 -0.5 0)
			(layer "B.SilkS")
			(effects
				(font
					(size 0.7 0.7)
					(thickness 0.15)
				)
				(justify left bottom mirror)
			)
		)
		(property "Value" "L_2n4_0.85A_0402"
			(at 0 -1.4 0)
			(layer "B.Fab")
			(effects
				(font
					(size 0.7 0.7)
					(thickness 0.15)
				)
				(justify left bottom mirror)
			)
		)
		(property "Datasheet" "https://www.murata.com/products/productdetail?partno=LQW15AN2N4B00%23"
			(at 0 0 0)
			(layer "B.Fab")
			(hide yes)
			(effects
				(font
					(size 1.27 1.27)
					(thickness 0.15)
				)
				(justify mirror)
			)
		)
		(property "Description" "Wirewound Inductor, 2.4 nH, 0.05 ohm, 15 GHz, 850 mA, 0402 [1005 Metric], LQW15AN"
			(at 0 0 0)
			(layer "B.Fab")
			(hide yes)
			(effects
				(font
					(size 1.27 1.27)
					(thickness 0.15)
				)
				(justify mirror)
			)
		)
		(property "Val" "2n4/0.85A"
			(at 0 0 180)
			(unlocked yes)
			(layer "B.Fab")
			(hide yes)
			(effects
				(font
					(size 1 1)
					(thickness 0.15)
				)
				(justify mirror)
			)
		)
		(property "Manufacturer" "Murata"
			(at 0 0 180)
			(unlocked yes)
			(layer "B.Fab")
			(hide yes)
			(effects
				(font
					(size 1 1)
					(thickness 0.15)
				)
				(justify mirror)
			)
		)
		(property "MPN" "LQW15AN2N4B00D"
			(at 0 0 180)
			(unlocked yes)
			(layer "B.Fab")
			(hide yes)
			(effects
				(font
					(size 1 1)
					(thickness 0.15)
				)
				(justify mirror)
			)
		)
		(property "ISat" "0.85 A"
			(at 0 0 180)
			(unlocked yes)
			(layer "B.Fab")
			(hide yes)
			(effects
				(font
					(size 1 1)
					(thickness 0.15)
				)
				(justify mirror)
			)
		)
		(property "IMax" "0.85 A"
			(at 0 0 180)
			(unlocked yes)
			(layer "B.Fab")
			(hide yes)
			(effects
				(font
					(size 1 1)
					(thickness 0.15)
				)
				(justify mirror)
			)
		)
		(property "Size" "1.0x0.5"
			(at 0 0 180)
			(unlocked yes)
			(layer "B.Fab")
			(hide yes)
			(effects
				(font
					(size 1 1)
					(thickness 0.15)
				)
				(justify mirror)
			)
		)
		(property "Author" "Antmicro"
			(at 0 0 180)
			(unlocked yes)
			(layer "B.Fab")
			(hide yes)
			(effects
				(font
					(size 1 1)
					(thickness 0.15)
				)
				(justify mirror)
			)
		)
		(property "License" "Apache-2.0"
			(at 0 0 180)
			(unlocked yes)
			(layer "B.Fab")
			(hide yes)
			(effects
				(font
					(size 1 1)
					(thickness 0.15)
				)
				(justify mirror)
			)
		)
		(sheetname "/2xRJ45/")
		(sheetfile "2xrj45.kicad_sch")
		(attr smd)
		(fp_rect
			(start -0.925 0.47)
			(end 0.925 -0.47)
			(stroke
				(width 0.05)
				(type default)
			)
			(fill no)
			(layer "B.CrtYd")
		)
		(fp_rect
			(start -0.499 0.249)
			(end 0.499 -0.249)
			(stroke
				(width 0.15)
				(type solid)
			)
			(fill no)
			(layer "B.Fab")
		)
		(fp_text user "License: Apache-2.0"
			(at -0.932 -5.17 0)
			(layer "B.Fab")
			(effects
				(font
					(size 0.7 0.7)
					(thickness 0.15)
				)
				(justify left bottom mirror)
			)
		)
		(fp_text user "Author: Antmicro"
			(at -0.932 -4.17 0)
			(layer "B.Fab")
			(effects
				(font
					(size 0.7 0.7)
					(thickness 0.15)
				)
				(justify left bottom mirror)
			)
		)
		(fp_text user "${REFERENCE}"
			(at -0.932 -3.168 0)
			(layer "B.Fab")
			(effects
				(font
					(size 0.7 0.7)
					(thickness 0.15)
				)
				(justify left bottom mirror)
			)
		)
		(pad "1" smd roundrect
			(at -0.48 0 180)
			(size 0.59 0.64)
			(layers "B.Cu" "B.Mask" "B.Paste")
			(roundrect_rratio 0.25)
			(net 135 "+1V88_CT")
			(pintype "passive")
		)
		(pad "2" smd roundrect
			(at 0.48 0 180)
			(size 0.59 0.64)
			(layers "B.Cu" "B.Mask" "B.Paste")
			(roundrect_rratio 0.25)
			(net 133 "/2xRJ45/P0_CT")
			(pintype "passive")
		)
	)
	(footprint "antmicro-footprints:TP_SMD_0.75mm"
		(layer "B.Cu")
		(at 142.25 55.25 180)
		(property "Reference" "TP2"
			(at -0.5 2.5 270)
			(layer "B.SilkS")
			(effects
				(font
					(size 0.7 0.7)
					(thickness 0.15)
				)
				(justify left bottom mirror)
			)
		)
		(property "Value" "TP_0.75mm_SMD"
			(at 0 -1.2 0)
			(layer "B.Fab")
			(effects
				(font
					(size 0.7 0.7)
					(thickness 0.15)
				)
				(justify left bottom mirror)
			)
		)
		(property "Description" "SMT test point"
			(at 0 0 0)
			(layer "B.Fab")
			(hide yes)
			(effects
				(font
					(size 1.27 1.27)
					(thickness 0.15)
				)
				(justify mirror)
			)
		)
		(property "MPN" ""
			(at 0 0 180)
			(unlocked yes)
			(layer "B.Fab")
			(hide yes)
			(effects
				(font
					(size 1 1)
					(thickness 0.15)
				)
				(justify mirror)
			)
		)
		(property "Manufacturer" ""
			(at 0 0 180)
			(unlocked yes)
			(layer "B.Fab")
			(hide yes)
			(effects
				(font
					(size 1 1)
					(thickness 0.15)
				)
				(justify mirror)
			)
		)
		(property "Author" "Antmicro"
			(at 0 0 180)
			(unlocked yes)
			(layer "B.Fab")
			(hide yes)
			(effects
				(font
					(size 1 1)
					(thickness 0.15)
				)
				(justify mirror)
			)
		)
		(property "License" "Apache-2.0"
			(at 0 0 180)
			(unlocked yes)
			(layer "B.Fab")
			(hide yes)
			(effects
				(font
					(size 1 1)
					(thickness 0.15)
				)
				(justify mirror)
			)
		)
		(sheetname "/Power input/")
		(sheetfile "power_input.kicad_sch")
		(attr exclude_from_pos_files exclude_from_bom)
		(fp_circle
			(center 0 0)
			(end 0.475 0)
			(stroke
				(width 0.05)
				(type default)
			)
			(fill no)
			(layer "B.CrtYd")
		)
		(fp_text user "License: Apache-2.0"
			(at -0.4 -5.101 0)
			(layer "B.Fab")
			(effects
				(font
					(size 0.7 0.7)
					(thickness 0.15)
				)
				(justify left bottom mirror)
			)
		)
		(fp_text user "Author: Antmicro"
			(at -0.4 -3.901 0)
			(layer "B.Fab")
			(effects
				(font
					(size 0.7 0.7)
					(thickness 0.15)
				)
				(justify left bottom mirror)
			)
		)
		(fp_text user "${REFERENCE}"
			(at -0.4 -2.7 0)
			(layer "B.Fab")
			(effects
				(font
					(size 0.7 0.7)
					(thickness 0.15)
				)
				(justify left bottom mirror)
			)
		)
		(pad "1" smd circle
			(at 0 0 180)
			(size 0.75 0.75)
			(layers "B.Cu" "B.Mask")
			(net 23 "GND")
			(pinfunction "1")
			(pintype "passive")
		)
	)
	(footprint "antmicro-footprints:R_0402_1005Metric"
		(layer "B.Cu")
		(at 162.381866 76.985117)
		(descr "Resistor SMD 0402")
		(tags "resistor SMD 0402")
		(property "Reference" "R127"
			(at 2.368134 0.014883 180)
			(layer "B.SilkS")
			(effects
				(font
					(size 0.7 0.7)
					(thickness 0.15)
				)
				(justify mirror)
			)
		)
		(property "Value" "R_1k_0402"
			(at -1.011843 -1.772047 180)
			(layer "B.Fab")
			(effects
				(font
					(size 0.7 0.7)
					(thickness 0.15)
				)
				(justify left bottom mirror)
			)
		)
		(property "Datasheet" "https://www.bourns.com/docs/product-datasheets/cr.pdf"
			(at 0 0 180)
			(layer "B.Fab")
			(hide yes)
			(effects
				(font
					(size 1.27 1.27)
					(thickness 0.15)
				)
				(justify mirror)
			)
		)
		(property "Description" "SMD Chip Resistor, 1 kohm, ± 1%, 63 mW, 0402 [1005 Metric], Thick Film, General Purpose"
			(at 0 0 180)
			(layer "B.Fab")
			(hide yes)
			(effects
				(font
					(size 1.27 1.27)
					(thickness 0.15)
				)
				(justify mirror)
			)
		)
		(property "MPN" "CR0402-FX-1001GLF"
			(at 0 0 0)
			(unlocked yes)
			(layer "B.Fab")
			(hide yes)
			(effects
				(font
					(size 1 1)
					(thickness 0.15)
				)
				(justify mirror)
			)
		)
		(property "Manufacturer" "Bourns"
			(at 0 0 0)
			(unlocked yes)
			(layer "B.Fab")
			(hide yes)
			(effects
				(font
					(size 1 1)
					(thickness 0.15)
				)
				(justify mirror)
			)
		)
		(property "License" "Apache-2.0"
			(at 0 0 0)
			(unlocked yes)
			(layer "B.Fab")
			(hide yes)
			(effects
				(font
					(size 1 1)
					(thickness 0.15)
				)
				(justify mirror)
			)
		)
		(property "Author" "Antmicro"
			(at 0 0 0)
			(unlocked yes)
			(layer "B.Fab")
			(hide yes)
			(effects
				(font
					(size 1 1)
					(thickness 0.15)
				)
				(justify mirror)
			)
		)
		(property "Val" "1k"
			(at 0 0 0)
			(unlocked yes)
			(layer "B.Fab")
			(hide yes)
			(effects
				(font
					(size 1 1)
					(thickness 0.15)
				)
				(justify mirror)
			)
		)
		(property "Tolerance" "1%"
			(at 0 0 0)
			(unlocked yes)
			(layer "B.Fab")
			(hide yes)
			(effects
				(font
					(size 1 1)
					(thickness 0.15)
				)
				(justify mirror)
			)
		)
		(sheetname "/X710-AT2 RSVD/")
		(sheetfile "x710-at2-rsvd.kicad_sch")
		(attr smd)
		(fp_rect
			(start -0.925 0.47)
			(end 0.925 -0.47)
			(stroke
				(width 0.05)
				(type default)
			)
			(fill no)
			(layer "B.CrtYd")
		)
		(fp_rect
			(start -0.5 0.25)
			(end 0.5 -0.25)
			(stroke
				(width 0.15)
				(type solid)
			)
			(fill no)
			(layer "B.Fab")
		)
		(fp_text user "License: Apache-2.0"
			(at -0.95 -5.169 180)
			(layer "B.Fab")
			(effects
				(font
					(size 0.7 0.7)
					(thickness 0.15)
				)
				(justify left bottom mirror)
			)
		)
		(fp_text user "Author: Antmicro"
			(at -0.95 -4.169 180)
			(layer "B.Fab")
			(effects
				(font
					(size 0.7 0.7)
					(thickness 0.15)
				)
				(justify left bottom mirror)
			)
		)
		(fp_text user "${REFERENCE}"
			(at -0.95 -3.168 180)
			(layer "B.Fab")
			(effects
				(font
					(size 0.7 0.7)
					(thickness 0.15)
				)
				(justify left bottom mirror)
			)
		)
		(pad "1" smd roundrect
			(at -0.48 0)
			(size 0.59 0.64)
			(layers "B.Cu" "B.Mask" "B.Paste")
			(roundrect_rratio 0.25)
			(net 101 "/X710-AT2 RSVD/RSVDD8_1P88V")
			(pintype "passive")
		)
		(pad "2" smd roundrect
			(at 0.48 0)
			(size 0.59 0.64)
			(layers "B.Cu" "B.Mask" "B.Paste")
			(roundrect_rratio 0.25)
			(net 18 "+1V88")
			(pintype "passive")
		)
	)
)
